# BASEBOARD_FAB2 (Tioga Pass) — schematic netlist excerpt (pin names and nets, part order shuffled) for the footprints in the layout excerpt that follows; sources: Cadence DE-HDL packaged netlist, KiCad conversion of Wiwynn_Tioga_Pass_MB.brd

C8E4  ST220U10VDM-LGP  IRP=2400MA  pkg SMD-TCG  page 241 : \1\ = P5V_STBY ; \2\ = GND
R3D26  RES  240 1.0% EMPTY  pkg 0402  page 90 : A = PVCCIO_CPU1 ; B = PU_CPU1_SAFE_MODE_BOOT

(kicad_pcb
	(version 20260206)
	(generator "pcbnew")
	(generator_version "10.0")
	(general
		(thickness 1.6)
		(legacy_teardrops no)
	)
	(paper "A4")
	(title_block
		(title "Wiwynn_Tioga_Pass_MB.brd")
		(comment 1 "Tioga Pass / footprints 624-625 of 4770")
	)
	(layers
		(0 "F.Cu" signal "TOP")
		(4 "In1.Cu" signal "L2GND")
		(6 "In2.Cu" signal "L3")
		(8 "In3.Cu" signal "L4GND")
		(10 "In4.Cu" signal "L5")
		(12 "In5.Cu" signal "L6GND")
		(14 "In6.Cu" signal "L7VCC")
		(16 "In7.Cu" signal "L8VCC")
		(18 "In8.Cu" signal "L9GND")
		(20 "In9.Cu" signal "L10")
		(22 "In10.Cu" signal "L11GND")
		(24 "In11.Cu" signal "L12")
		(26 "In12.Cu" signal "L13GND")
		(2 "B.Cu" signal "BOTTOM")
		(9 "F.Adhes" user "F.Adhesive")
		(11 "B.Adhes" user "B.Adhesive")
		(13 "F.Paste" user "Package Geometry/Pastemask Top")
		(15 "B.Paste" user "Package Geometry/Pastemask Bottom")
		(5 "F.SilkS" user "Ref Des/Silkscreen Top")
		(7 "B.SilkS" user "Ref Des/Silkscreen Bottom")
		(1 "F.Mask" user "Board Geometry/Soldermask Top")
		(3 "B.Mask" user "Board Geometry/Soldermask Bottom")
		(17 "Dwgs.User" user "User.Drawings")
		(19 "Cmts.User" user "User.Comments")
		(21 "Eco1.User" user "User.Eco1")
		(23 "Eco2.User" user "User.Eco2")
		(25 "Edge.Cuts" user "Board Geometry/Outline")
		(27 "Margin" user)
		(31 "F.CrtYd" user "Package Geometry/Place Bound Top")
		(29 "B.CrtYd" user "Package Geometry/Place Bound Bottom")
		(35 "F.Fab" user "Ref Des/Assembly Top")
		(33 "B.Fab" user "Ref Des/Assembly Bottom")
	)
	(footprint ""
		(layer "F.Cu")
		(at 112.4458 -69.85)
		(property "Reference" "R3D26"
			(at 0 0 0)
			(layer "F.SilkS")
			(hide yes)
			(effects
				(font
					(size 1.27 1.27)
				)
			)
		)
		(property "Value" ""
			(at 0 0 0)
			(layer "F.Fab")
			(effects
				(font
					(size 1.27 1.27)
				)
			)
		)
		(duplicate_pad_numbers_are_jumpers no)
		(fp_poly
			(pts
				(xy -0.2794 -0.1016) (xy 0.2794 -0.1016) (xy 0.2794 0.9906) (xy -0.2794 0.9906)
			)
			(stroke
				(width 0)
				(type default)
			)
			(fill no)
			(layer "F.CrtYd")
		)
		(fp_line
			(start -0.2794 -0.1016)
			(end -0.2794 0.9906)
			(stroke
				(width 0.1)
				(type default)
			)
			(layer "F.Fab")
		)
		(fp_line
			(start -0.2794 0.9906)
			(end 0.2794 0.9906)
			(stroke
				(width 0.1)
				(type default)
			)
			(layer "F.Fab")
		)
		(fp_line
			(start 0.2794 -0.1016)
			(end -0.2794 -0.1016)
			(stroke
				(width 0.1)
				(type default)
			)
			(layer "F.Fab")
		)
		(fp_line
			(start 0.2794 0.9906)
			(end 0.2794 -0.1016)
			(stroke
				(width 0.1)
				(type default)
			)
			(layer "F.Fab")
		)
		(pad "1" smd rect
			(at 0 0)
			(size 0.508 0.508)
			(layers "F.Cu" "F.Mask" "F.Paste")
			(net "PVCCIO_CPU1")
		)
		(pad "2" smd rect
			(at 0 0.889)
			(size 0.508 0.508)
			(layers "F.Cu" "F.Mask" "F.Paste")
			(net "PU_CPU1_SAFE_MODE_BOOT")
		)
		(zone
			(layer "F.Cu")
			(hatch none 0.5)
			(connect_pads
				(clearance 0)
			)
			(min_thickness 0.25)
			(keepout
				(tracks allowed)
				(vias not_allowed)
				(pads allowed)
				(copperpour not_allowed)
				(footprints allowed)
			)
			(placement
				(enabled no)
				(sheetname "")
			)
			(fill
				(thermal_gap 0.5)
				(thermal_bridge_width 0.5)
				(island_removal_mode 0)
			)
			(polygon
				(pts
					(xy 112.1918 -69.596) (xy 112.6998 -69.596) (xy 112.6998 -69.215) (xy 112.1918 -69.215)
				)
			)
		)
		(zone
			(layer "F.Cu")
			(hatch none 0.5)
			(connect_pads
				(clearance 0)
			)
			(min_thickness 0.25)
			(keepout
				(tracks not_allowed)
				(vias allowed)
				(pads allowed)
				(copperpour not_allowed)
				(footprints allowed)
			)
			(placement
				(enabled no)
				(sheetname "")
			)
			(fill
				(thermal_gap 0.5)
				(thermal_bridge_width 0.5)
				(island_removal_mode 0)
			)
			(polygon
				(pts
					(xy 112.1918 -69.215) (xy 112.6998 -69.215) (xy 112.6998 -69.596) (xy 112.1918 -69.596)
				)
			)
		)
	)
	(footprint ""
		(layer "F.Cu")
		(at 399.48231 -61.962538 -90)
		(property "Reference" "C8E4"
			(at 0 0 270)
			(layer "F.SilkS")
			(hide yes)
			(effects
				(font
					(size 1.27 1.27)
				)
			)
		)
		(property "Value" "*"
			(at 0 -9.7155 270)
			(unlocked yes)
			(layer "F.Fab")
			(hide yes)
			(effects
				(font
					(size 1.27 1.016)
					(thickness 0.1524)
				)
			)
		)
		(property "Device Type" "ST220U10VDM-LGP_SMD-TCG-ST220UA"
			(at 0 -11.2395 270)
			(unlocked yes)
			(layer "F.Fab")
			(hide yes)
			(effects
				(font
					(size 1.27 1.016)
					(thickness 0.1524)
				)
			)
		)
		(duplicate_pad_numbers_are_jumpers no)
		(fp_line
			(start -2.286 4.8768)
			(end -2.286 2.032)
			(stroke
				(width 0.1524)
				(type default)
			)
			(layer "F.SilkS")
		)
		(fp_line
			(start 2.286 4.8768)
			(end -2.286 4.8768)
			(stroke
				(width 0.1524)
				(type default)
			)
			(layer "F.SilkS")
		)
		(fp_line
			(start 2.286 2.032)
			(end 2.286 4.8768)
			(stroke
				(width 0.1524)
				(type default)
			)
			(layer "F.SilkS")
		)
		(fp_line
			(start 2.286 -2.032)
			(end 2.286 -4.8768)
			(stroke
				(width 0.1524)
				(type default)
			)
			(layer "F.SilkS")
		)
		(fp_line
			(start 2.1082 -4.699)
			(end -2.1082 -4.699)
			(stroke
				(width 0.508)
				(type default)
			)
			(layer "F.SilkS")
		)
		(fp_line
			(start -2.286 -4.8768)
			(end -2.286 -2.032)
			(stroke
				(width 0.1524)
				(type default)
			)
			(layer "F.SilkS")
		)
		(fp_line
			(start 2.286 -4.8768)
			(end -2.286 -4.8768)
			(stroke
				(width 0.1524)
				(type default)
			)
			(layer "F.SilkS")
		)
		(fp_rect
			(start -2.1463 3.6449)
			(end 2.1463 -3.6449)
			(stroke
				(width 0)
				(type default)
			)
			(fill no)
			(layer "F.CrtYd")
		)
		(fp_poly
			(pts
				(xy -2.54 4.953) (xy -2.54 4.2926) (xy -3.81 4.2926) (xy -3.81 -4.2926) (xy -2.54 -4.2926) (xy -2.54 -4.953)
				(xy 2.54 -4.953) (xy 2.54 -4.2926) (xy 3.81 -4.2926) (xy 3.81 -1.6256) (xy 2.1463 -1.6256) (xy 2.1463 -3.6449)
				(xy -2.1463 -3.6449) (xy -2.1463 3.6449) (xy 2.1463 3.6449) (xy 2.1463 -1.6129) (xy 3.81 -1.6129)
				(xy 3.81 4.2926) (xy 2.54 4.2926) (xy 2.54 4.953)
			)
			(stroke
				(width 0)
				(type default)
			)
			(fill no)
			(layer "F.CrtYd")
		)
		(fp_rect
			(start -2.54 4.953)
			(end 2.54 -4.953)
			(stroke
				(width 0)
				(type default)
			)
			(fill no)
			(layer "F.Fab")
		)
		(fp_rect
			(start -3.81 4.2926)
			(end -2.54 -4.2926)
			(stroke
				(width 0)
				(type default)
			)
			(fill no)
			(layer "F.Fab")
		)
		(fp_rect
			(start 2.54 4.2926)
			(end 3.81 -4.2926)
			(stroke
				(width 0)
				(type default)
			)
			(fill no)
			(layer "F.Fab")
		)
		(pad "1" smd rect
			(at 0 -3.1496 270)
			(size 2.413 2.286)
			(layers "F.Cu" "F.Mask" "F.Paste")
			(net "P5V_STBY")
		)
		(pad "2" smd rect
			(at 0 3.1496 270)
			(size 2.413 2.286)
			(layers "F.Cu" "F.Mask" "F.Paste")
			(net "GND")
		)
		(zone
			(layer "F.Cu")
			(hatch none 0.5)
			(connect_pads
				(clearance 0)
			)
			(min_thickness 0.25)
			(keepout
				(tracks allowed)
				(vias not_allowed)
				(pads allowed)
				(copperpour not_allowed)
				(footprints allowed)
			)
			(placement
				(enabled no)
				(sheetname "")
			)
			(fill
				(thermal_gap 0.5)
				(thermal_bridge_width 0.5)
				(island_removal_mode 0)
			)
			(polygon
				(pts
					(xy 394.88491 -63.473838) (xy 394.88491 -60.451238) (xy 397.78051 -60.451238) (xy 398.11071 -60.451238)
					(xy 398.11071 -63.473838) (xy 397.78051 -63.473838)
				)
			)
		)
		(zone
			(layer "F.Cu")
			(hatch none 0.5)
			(connect_pads
				(clearance 0)
			)
			(min_thickness 0.25)
			(keepout
				(tracks allowed)
				(vias not_allowed)
				(pads allowed)
				(copperpour not_allowed)
				(footprints allowed)
			)
			(placement
				(enabled no)
				(sheetname "")
			)
			(fill
				(thermal_gap 0.5)
				(thermal_bridge_width 0.5)
				(island_removal_mode 0)
			)
			(polygon
				(pts
					(xy 401.17141 -60.451238) (xy 404.07971 -60.451238) (xy 404.07971 -63.473838) (xy 401.18411 -63.473838)
					(xy 400.85391 -63.473838) (xy 400.85391 -60.451238)
				)
			)
		)
	)
)
